(kicad_pcb
	(version 20240108)
	(generator "pcbnew")
	(generator_version "8.0")
	(general
		(thickness 1.62)
		(legacy_teardrops no)
	)
	(paper "A4")
	(title_block
		(title "Jetson Orin Baseboard")
		(date "2025-03-12")
		(rev "1.3.4")
		(company "Antmicro Ltd")
		(comment 1 "www.antmicro.com")
		(comment 9 "footprints 252-253 of 677")
	)
	(layers
		(0 "F.Cu" signal)
		(1 "In1.Cu" signal)
		(2 "In2.Cu" signal)
		(3 "In3.Cu" signal)
		(4 "In4.Cu" jumper)
		(5 "In5.Cu" signal)
		(6 "In6.Cu" signal)
		(31 "B.Cu" signal)
		(32 "B.Adhes" user "B.Adhesive")
		(33 "F.Adhes" user "F.Adhesive")
		(34 "B.Paste" user)
		(35 "F.Paste" user)
		(36 "B.SilkS" user "B.Silkscreen")
		(37 "F.SilkS" user "F.Silkscreen")
		(38 "B.Mask" user)
		(39 "F.Mask" user)
		(40 "Dwgs.User" user "User.Drawings")
		(41 "Cmts.User" user "User.Comments")
		(42 "Eco1.User" user "User.Eco1")
		(43 "Eco2.User" user "User.Eco2")
		(44 "Edge.Cuts" user)
		(45 "Margin" user)
		(46 "B.CrtYd" user "B.Courtyard")
		(47 "F.CrtYd" user "F.Courtyard")
		(48 "B.Fab" user)
		(49 "F.Fab" user)
	)
	(footprint "antmicro-footprints:MLP44-24L_4x4x0.75mm"
		(layer "F.Cu")
		(at 77.15 89.415)
		(property "Reference" "U40"
			(at -2.09 3.445 0)
			(layer "F.SilkS")
			(effects
				(font
					(size 0.7 0.7)
					(thickness 0.15)
				)
				(justify left bottom)
			)
		)
		(property "Value" "SIC431AED-T1-GE3"
			(at 0 3.6 0)
			(layer "F.Fab")
			(effects
				(font
					(size 0.7 0.7)
					(thickness 0.15)
				)
				(justify left bottom)
			)
		)
		(property "Footprint" "antmicro-footprints:MLP44-24L_4x4x0.75mm"
			(at 0 0 0)
			(layer "F.Fab")
			(hide yes)
			(effects
				(font
					(size 1.27 1.27)
					(thickness 0.15)
				)
			)
		)
		(property "Datasheet" "https://www.vishay.com/docs/74589/sic431.pdf"
			(at 0 0 0)
			(layer "F.Fab")
			(hide yes)
			(effects
				(font
					(size 1.27 1.27)
					(thickness 0.15)
				)
			)
		)
		(property "Author" "Antmicro"
			(at 0 0 0)
			(layer "F.Fab")
			(hide yes)
			(effects
				(font
					(size 1 1)
					(thickness 0.15)
				)
			)
		)
		(property "License" "Apache-2.0"
			(at 0 0 0)
			(layer "F.Fab")
			(hide yes)
			(effects
				(font
					(size 1 1)
					(thickness 0.15)
				)
			)
		)
		(property "MPN" "SIC431AED-T1-GE3 "
			(at 0 0 0)
			(layer "F.Fab")
			(hide yes)
			(effects
				(font
					(size 1 1)
					(thickness 0.15)
				)
			)
		)
		(property "Manufacturer" "Vishay"
			(at 0 0 0)
			(layer "F.Fab")
			(hide yes)
			(effects
				(font
					(size 1 1)
					(thickness 0.15)
				)
			)
		)
		(sheetname "Supply")
		(sheetfile "supply.kicad_sch")
		(attr smd)
		(net_tie_pad_groups "1,2,26" "3,4,27" "5,6,7,8,9")
		(fp_line
			(start -2.11 -1.38)
			(end -2.11 -2.1)
			(stroke
				(width 0.15)
				(type solid)
			)
			(layer "F.SilkS")
		)
		(fp_line
			(start -2.11 2.11)
			(end -2.11 1.39)
			(stroke
				(width 0.15)
				(type solid)
			)
			(layer "F.SilkS")
		)
		(fp_line
			(start -1.89 -2.1)
			(end -2.11 -2.1)
			(stroke
				(width 0.15)
				(type solid)
			)
			(layer "F.SilkS")
		)
		(fp_line
			(start -1.89 2.11)
			(end -2.11 2.11)
			(stroke
				(width 0.15)
				(type solid)
			)
			(layer "F.SilkS")
		)
		(fp_line
			(start 1.44 2.11)
			(end 2.11 2.11)
			(stroke
				(width 0.15)
				(type solid)
			)
			(layer "F.SilkS")
		)
		(fp_line
			(start 1.89 -2.11)
			(end 2.11 -2.11)
			(stroke
				(width 0.15)
				(type solid)
			)
			(layer "F.SilkS")
		)
		(fp_line
			(start 2.11 -2.11)
			(end 2.11 -1.69)
			(stroke
				(width 0.15)
				(type solid)
			)
			(layer "F.SilkS")
		)
		(fp_line
			(start 2.11 2.11)
			(end 2.11 1.84)
			(stroke
				(width 0.15)
				(type solid)
			)
			(layer "F.SilkS")
		)
		(fp_circle
			(center -2.25 -1.15)
			(end -2.2 -1.15)
			(stroke
				(width 0.15)
				(type solid)
			)
			(fill solid)
			(layer "F.SilkS")
		)
		(fp_line
			(start -2.55 -2.55)
			(end 2.55 -2.55)
			(stroke
				(width 0.05)
				(type solid)
			)
			(layer "F.CrtYd")
		)
		(fp_line
			(start -2.55 2.55)
			(end -2.55 -2.55)
			(stroke
				(width 0.05)
				(type solid)
			)
			(layer "F.CrtYd")
		)
		(fp_line
			(start 2.55 -2.55)
			(end 2.55 2.55)
			(stroke
				(width 0.05)
				(type solid)
			)
			(layer "F.CrtYd")
		)
		(fp_line
			(start 2.55 2.55)
			(end -2.55 2.55)
			(stroke
				(width 0.05)
				(type solid)
			)
			(layer "F.CrtYd")
		)
		(fp_line
			(start -2 -1)
			(end -2 2)
			(stroke
				(width 0.15)
				(type solid)
			)
			(layer "F.Fab")
		)
		(fp_line
			(start -2 2)
			(end 2 2)
			(stroke
				(width 0.15)
				(type solid)
			)
			(layer "F.Fab")
		)
		(fp_line
			(start -1 -2)
			(end -2 -1)
			(stroke
				(width 0.15)
				(type solid)
			)
			(layer "F.Fab")
		)
		(fp_line
			(start 2 -2)
			(end -1 -2)
			(stroke
				(width 0.15)
				(type solid)
			)
			(layer "F.Fab")
		)
		(fp_line
			(start 2 2)
			(end 2 -2)
			(stroke
				(width 0.15)
				(type solid)
			)
			(layer "F.Fab")
		)
		(fp_text user "License: Apache-2.0"
			(at -2.7 5.6 0)
			(layer "F.Fab")
			(hide yes)
			(effects
				(font
					(size 0.7 0.7)
					(thickness 0.15)
				)
				(justify left bottom)
			)
		)
		(fp_text user "License: "
			(at -2.9 5.6 0)
			(layer "F.Fab")
			(hide yes)
			(effects
				(font
					(size 0.7 0.7)
					(thickness 0.15)
				)
				(justify left bottom)
			)
		)
		(fp_text user "Author: Antmicro"
			(at -2.9 8 0)
			(layer "F.Fab")
			(hide yes)
			(effects
				(font
					(size 0.7 0.7)
					(thickness 0.15)
				)
				(justify left bottom)
			)
		)
		(fp_text user "${REFERENCE}"
			(at -2.9 6.8 0)
			(layer "F.Fab")
			(hide yes)
			(effects
				(font
					(size 0.7 0.7)
					(thickness 0.15)
				)
				(justify left bottom)
			)
		)
		(pad "1" smd roundrect
			(at -1.94 -0.825 90)
			(size 0.3 0.725)
			(layers "F.Cu" "F.Paste" "F.Mask")
			(roundrect_rratio 0.25)
			(net 115 "VCC")
			(pinfunction "V_{IN}")
			(pintype "power_in")
		)
		(pad "2" smd roundrect
			(at -1.94 -0.375 90)
			(size 0.3 0.725)
			(layers "F.Cu" "F.Paste" "F.Mask")
			(roundrect_rratio 0.25)
			(net 115 "VCC")
			(pinfunction "V_{IN}")
			(pintype "passive")
		)
		(pad "3" smd roundrect
			(at -1.94 0.525 90)
			(size 0.3 0.725)
			(layers "F.Cu" "F.Paste" "F.Mask")
			(roundrect_rratio 0.25)
			(net 1 "GND")
			(pinfunction "P_{GND}")
			(pintype "passive")
		)
		(pad "4" smd roundrect
			(at -1.94 0.975 90)
			(size 0.3 0.725)
			(layers "F.Cu" "F.Paste" "F.Mask")
			(roundrect_rratio 0.25)
			(net 1 "GND")
			(pinfunction "P_{GND}")
			(pintype "passive")
		)
		(pad "5" smd custom
			(at -1.475 1.94)
			(size 0.3 0.3)
			(layers "F.Cu" "F.Paste" "F.Mask")
			(net 643 "/Supply/3V3_SW")
			(pinfunction "SW")
			(pintype "passive")
			(options
				(clearance outline)
				(anchor circle)
			)
			(primitives
				(gr_poly
					(pts
						(xy -0.15 -0.2875) (xy -0.144291 -0.316201) (xy -0.128033 -0.340533) (xy -0.103701 -0.356791)
						(xy -0.075 -0.3625) (xy 0.075 -0.3625) (xy 0.103701 -0.356791) (xy 0.128033 -0.340533) (xy 0.144291 -0.316201)
						(xy 0.15 -0.2875) (xy 0.15 0.2875) (xy 0.144291 0.316201) (xy 0.128033 0.340533) (xy 0.103701 0.356791)
						(xy 0.075 0.3625) (xy -0.075 0.3625) (xy -0.103701 0.356791) (xy -0.128033 0.340533) (xy -0.144291 0.316201)
						(xy -0.15 0.2875)
					)
					(width 0)
					(fill yes)
				)
				(gr_poly
					(pts
						(xy -0.15 -0.3625) (xy 2.2 -0.3625) (xy 2.2 -0.0875) (xy -0.15 -0.0875)
					)
					(width 0)
					(fill yes)
				)
			)
		)
		(pad "6" smd roundrect
			(at -1.025 1.94)
			(size 0.3 0.725)
			(layers "F.Cu" "F.Paste" "F.Mask")
			(roundrect_rratio 0.25)
			(net 643 "/Supply/3V3_SW")
			(pinfunction "SW")
			(pintype "passive")
		)
		(pad "7" smd roundrect
			(at -0.575 1.94)
			(size 0.3 0.725)
			(layers "F.Cu" "F.Paste" "F.Mask")
			(roundrect_rratio 0.25)
			(net 643 "/Supply/3V3_SW")
			(pinfunction "SW")
			(pintype "passive")
		)
		(pad "8" smd roundrect
			(at 0.125 1.94)
			(size 0.3 0.725)
			(layers "F.Cu" "F.Paste" "F.Mask")
			(roundrect_rratio 0.25)
			(net 643 "/Supply/3V3_SW")
			(pinfunction "SW")
			(pintype "passive")
		)
		(pad "9" smd roundrect
			(at 0.575 1.94)
			(size 0.3 0.725)
			(layers "F.Cu" "F.Paste" "F.Mask")
			(roundrect_rratio 0.25)
			(net 643 "/Supply/3V3_SW")
			(pinfunction "SW")
			(pintype "passive")
		)
		(pad "10" smd roundrect
			(at 1.025 1.935)
			(size 0.3 0.725)
			(layers "F.Cu" "F.Paste" "F.Mask")
			(roundrect_rratio 0.25)
			(net 785 "unconnected-(U40-GL-Pad10)_1")
			(pinfunction "GL")
			(pintype "passive+no_connect")
		)
		(pad "11" smd roundrect
			(at 1.94 1.425 90)
			(size 0.3 0.725)
			(layers "F.Cu" "F.Paste" "F.Mask")
			(roundrect_rratio 0.25)
			(net 756 "unconnected-(U40-GL-Pad10)")
			(pinfunction "GL")
			(pintype "passive+no_connect")
		)
		(pad "12" smd roundrect
			(at 1.94 0.975 90)
			(size 0.3 0.725)
			(layers "F.Cu" "F.Paste" "F.Mask")
			(roundrect_rratio 0.25)
			(net 642 "/Supply/3V3_VDRV")
			(pinfunction "V_{DRV}")
			(pintype "passive")
		)
		(pad "13" smd roundrect
			(at 1.94 0.525 90)
			(size 0.3 0.725)
			(layers "F.Cu" "F.Paste" "F.Mask")
			(roundrect_rratio 0.25)
			(net 1 "GND")
			(pinfunction "P_{GND}")
			(pintype "power_in")
		)
		(pad "14" smd roundrect
			(at 1.94 0.075 90)
			(size 0.3 0.725)
			(layers "F.Cu" "F.Paste" "F.Mask")
			(roundrect_rratio 0.25)
			(net 757 "unconnected-(U40-P_{GOOD}-Pad14)")
			(pinfunction "P_{GOOD}")
			(pintype "output+no_connect")
		)
		(pad "15" smd roundrect
			(at 1.94 -0.375 90)
			(size 0.3 0.725)
			(layers "F.Cu" "F.Paste" "F.Mask")
			(roundrect_rratio 0.25)
			(net 177 "/Supply/3V3_VDD")
			(pinfunction "V_{DD}")
			(pintype "passive")
		)
		(pad "16" smd roundrect
			(at 1.94 -0.825 90)
			(size 0.3 0.725)
			(layers "F.Cu" "F.Paste" "F.Mask")
			(roundrect_rratio 0.25)
			(net 1 "GND")
			(pinfunction "A_{GND}")
			(pintype "power_in")
		)
		(pad "17" smd roundrect
			(at 1.94 -1.275 90)
			(size 0.3 0.725)
			(layers "F.Cu" "F.Paste" "F.Mask")
			(roundrect_rratio 0.25)
			(net 711 "/Supply/3V3_FB")
			(pinfunction "FB")
			(pintype "passive")
		)
		(pad "18" smd roundrect
			(at 1.475 -1.94)
			(size 0.3 0.725)
			(layers "F.Cu" "F.Paste" "F.Mask")
			(roundrect_rratio 0.25)
			(net 641 "/Supply/3V3_OUT")
			(pinfunction "V_{OUT}")
			(pintype "passive")
		)
		(pad "19" smd roundrect
			(at 1.025 -1.94)
			(size 0.3 0.725)
			(layers "F.Cu" "F.Paste" "F.Mask")
			(roundrect_rratio 0.25)
			(net 771 "/Supply/3V3_EN")
			(pinfunction "EN")
			(pintype "input")
		)
		(pad "20" smd roundrect
			(at 0.575 -1.94)
			(size 0.3 0.725)
			(layers "F.Cu" "F.Paste" "F.Mask")
			(roundrect_rratio 0.25)
			(net 684 "/Supply/3V3_MODE2")
			(pinfunction "MODE2")
			(pintype "input")
		)
		(pad "21" smd roundrect
			(at 0.125 -1.94)
			(size 0.3 0.725)
			(layers "F.Cu" "F.Paste" "F.Mask")
			(roundrect_rratio 0.25)
			(net 687 "/Supply/3V3_MODE1")
			(pinfunction "MODE1")
			(pintype "input")
		)
		(pad "22" smd roundrect
			(at -0.575 -1.94)
			(size 0.3 0.725)
			(layers "F.Cu" "F.Paste" "F.Mask")
			(roundrect_rratio 0.25)
			(net 115 "VCC")
			(pinfunction "V_{IN}")
			(pintype "passive")
		)
		(pad "23" smd roundrect
			(at -1.025 -1.94)
			(size 0.3 0.725)
			(layers "F.Cu" "F.Paste" "F.Mask")
			(roundrect_rratio 0.25)
			(net 358 "/Supply/3V3_BOOT")
			(pinfunction "BOOT")
			(pintype "passive")
		)
		(pad "24" smd roundrect
			(at -1.475 -1.94)
			(size 0.3 0.725)
			(layers "F.Cu" "F.Paste" "F.Mask")
			(roundrect_rratio 0.25)
			(net 758 "/Supply/3V3_PHASE")
			(pinfunction "PHASE")
			(pintype "passive")
		)
		(pad "25" smd rect
			(at 0.49 -0.75 180)
			(size 1.575 1.05)
			(layers "F.Cu" "F.Paste" "F.Mask")
			(net 1 "GND")
			(pinfunction "A_{GND}")
			(pintype "passive")
		)
		(pad "26" smd rect
			(at -1.175 -0.75 180)
			(size 1.15 1.05)
			(layers "F.Cu" "F.Paste" "F.Mask")
			(net 115 "VCC")
			(pinfunction "V_{IN}")
			(pintype "passive")
		)
		(pad "27" smd custom
			(at -0.75 0.775)
			(size 1 1)
			(layers "F.Cu" "F.Paste" "F.Mask")
			(net 1 "GND")
			(pinfunction "P_{GND}")
			(pintype "passive")
			(options
				(clearance outline)
				(anchor rect)
			)
			(primitives
				(gr_poly
					(pts
						(xy -1 0.5) (xy -1 -0.7) (xy 1.825 -0.7) (xy 1.825 -0.245) (xy 1.175 -0.245) (xy 1.175 0.5)
					)
					(width 0)
					(fill yes)
				)
			)
		)
		(pad "28" smd rect
			(at 0.985 0.99 180)
			(size 0.58 0.38)
			(layers "F.Cu" "F.Paste" "F.Mask")
			(net 786 "unconnected-(U40-GL-Pad10)_2")
			(pinfunction "GL")
			(pintype "passive+no_connect")
		)
	)
	(footprint "antmicro-footprints:L_Bourns-SRP5030CA"
		(layer "F.Cu")
		(at 73.245 95.97 180)
		(property "Reference" "L1"
			(at -4.135 -2.85 0)
			(layer "F.SilkS")
			(effects
				(font
					(size 0.7 0.7)
					(thickness 0.15)
				)
				(justify right bottom)
			)
		)
		(property "Value" "L_560n_17.7A_Bourns-SRP5030CA"
			(at 0 4.241 0)
			(layer "F.Fab")
			(effects
				(font
					(size 0.7 0.7)
					(thickness 0.15)
				)
				(justify right bottom)
			)
		)
		(property "Footprint" "antmicro-footprints:L_Bourns-SRP5030CA"
			(at 0 0 180)
			(layer "F.Fab")
			(hide yes)
			(effects
				(font
					(size 1.27 1.27)
					(thickness 0.15)
				)
			)
		)
		(property "Datasheet" "https://www.bourns.com/docs/Product-Datasheets/SRP5030CA.pdf"
			(at 0 0 180)
			(layer "F.Fab")
			(hide yes)
			(effects
				(font
					(size 1.27 1.27)
					(thickness 0.15)
				)
			)
		)
		(property "Author" "Antmicro"
			(at 146.49 191.94 0)
			(layer "F.Fab")
			(hide yes)
			(effects
				(font
					(size 1 1)
					(thickness 0.15)
				)
			)
		)
		(property "IMax" "17.7 A"
			(at 146.49 191.94 0)
			(layer "F.Fab")
			(hide yes)
			(effects
				(font
					(size 1 1)
					(thickness 0.15)
				)
			)
		)
		(property "ISat" "22.2 A"
			(at 146.49 191.94 0)
			(layer "F.Fab")
			(hide yes)
			(effects
				(font
					(size 1 1)
					(thickness 0.15)
				)
			)
		)
		(property "License" "Apache-2.0"
			(at 146.49 191.94 0)
			(layer "F.Fab")
			(hide yes)
			(effects
				(font
					(size 1 1)
					(thickness 0.15)
				)
			)
		)
		(property "MPN" "SRP5030CA-R56M"
			(at 146.49 191.94 0)
			(layer "F.Fab")
			(hide yes)
			(effects
				(font
					(size 1 1)
					(thickness 0.15)
				)
			)
		)
		(property "Manufacturer" "Bourns"
			(at 146.49 191.94 0)
			(layer "F.Fab")
			(hide yes)
			(effects
				(font
					(size 1 1)
					(thickness 0.15)
				)
			)
		)
		(property "Size" "5.5x5.3"
			(at 146.49 191.94 0)
			(layer "F.Fab")
			(hide yes)
			(effects
				(font
					(size 1 1)
					(thickness 0.15)
				)
			)
		)
		(property "Val" "560n/17.7A"
			(at 146.49 191.94 0)
			(layer "F.Fab")
			(hide yes)
			(effects
				(font
					(size 1 1)
					(thickness 0.15)
				)
			)
		)
		(sheetname "Supply")
		(sheetfile "supply.kicad_sch")
		(attr smd)
		(fp_line
			(start 2.65 2.75)
			(end 2.65 -2.75)
			(stroke
				(width 0.15)
				(type solid)
			)
			(layer "F.SilkS")
		)
		(fp_line
			(start -2.65 2.75)
			(end 2.65 2.75)
			(stroke
				(width 0.15)
				(type solid)
			)
			(layer "F.SilkS")
		)
		(fp_line
			(start -2.65 2.75)
			(end -2.65 -2.75)
			(stroke
				(width 0.15)
				(type solid)
			)
			(layer "F.SilkS")
		)
		(fp_line
			(start -2.65 -2.75)
			(end 2.65 -2.75)
			(stroke
				(width 0.15)
				(type solid)
			)
			(layer "F.SilkS")
		)
		(fp_rect
			(start -2.89 -2.99)
			(end 2.89 2.99)
			(stroke
				(width 0.05)
				(type solid)
			)
			(fill none)
			(layer "F.CrtYd")
		)
		(fp_line
			(start 2.65 2.75)
			(end -2.65 2.75)
			(stroke
				(width 0.15)
				(type solid)
			)
			(layer "F.Fab")
		)
		(fp_line
			(start 2.65 -2.75)
			(end 2.65 2.75)
			(stroke
				(width 0.15)
				(type solid)
			)
			(layer "F.Fab")
		)
		(fp_line
			(start -2.65 2.75)
			(end -2.65 -2.75)
			(stroke
				(width 0.15)
				(type solid)
			)
			(layer "F.Fab")
		)
		(fp_line
			(start -2.65 -2.75)
			(end 2.65 -2.75)
			(stroke
				(width 0.15)
				(type solid)
			)
			(layer "F.Fab")
		)
		(fp_text user "${REFERENCE}"
			(at -2.89 8.641 0)
			(layer "F.Fab")
			(hide yes)
			(effects
				(font
					(size 0.7 0.7)
					(thickness 0.15)
				)
				(justify right bottom)
			)
		)
		(fp_text user "Author: Antmicro"
			(at -2.89 7.441 0)
			(layer "F.Fab")
			(hide yes)
			(effects
				(font
					(size 0.7 0.7)
					(thickness 0.15)
				)
				(justify right bottom)
			)
		)
		(fp_text user "License: Apache-2.0"
			(at -2.89 6.241 0)
			(layer "F.Fab")
			(hide yes)
			(effects
				(font
					(size 0.7 0.7)
					(thickness 0.15)
				)
				(justify right bottom)
			)
		)
		(pad "1" smd roundrect
			(at -1.625 0 180)
			(size 1.25 4.7)
			(layers "F.Cu" "F.Paste" "F.Mask")
			(roundrect_rratio 0.1)
			(net 643 "/Supply/3V3_SW")
			(pintype "passive")
		)
		(pad "2" smd roundrect
			(at 1.625 0 180)
			(size 1.25 4.7)
			(layers "F.Cu" "F.Paste" "F.Mask")
			(roundrect_rratio 0.1)
			(net 641 "/Supply/3V3_OUT")
			(pintype "passive")
		)
	)
)
